# BARRELEYE-G2-EXPANDER-EVT-HW-EBOM-X00-20161124-add_2nd_source_X06-20161207-Final.xls — TBD AVL Qual (bom)
| NOTES: |  |  |  |  |  |  |
| The following items are alternates to the items listed in the Critical Components Qual tab. |  |  |  |  |  |  |
| These components will be included on near future, non-customer builds for validation and approval by both Customer and the ODM. |  |  |  |  |  |  |
| Item Description | ODM P/N | Customer PN | Vendor | Vendor PN | Build ?? | Estimated Completion Date |
| SATA connectors (black) |  |  |  |  |  |  |
| -  Alternate |  |  |  |  |  |  |
| SATA connectors (blue) |  |  |  |  |  |  |
| -  Alternate |  |  |  |  |  |  |
| PCIe retention |  |  |  |  |  |  |
| -  Alternate |  |  |  |  |  |  |
| RTC XTAL |  |  |  |  |  |  |
| -  Alternate |  |  |  |  |  |  |
| XTAL |  |  |  |  |  |  |
| -  Alternate |  |  |  |  |  |  |
